G04 ================== begin FILE IDENTIFICATION RECORD ==================*
G04 Layout Name:  12523-1.brd*
G04 Film Name:    TSMD*
G04 File Format:  Gerber RS274X*
G04 File Origin:  Cadence Allegro 16.2-s031*
G04 Origin Date:  Fri Oct 19 14:59:10 2012*
G04 *
G04 Layer:  VIA CLASS/PASTEMASK_TOP*
G04 Layer:  PIN/PASTEMASK_TOP*
G04 Layer:  PACKAGE GEOMETRY/PASTEMASK_TOP*
G04 Layer:  DRAWING FORMAT/LAYER_PCB_STORY*
G04 Layer:  DRAWING FORMAT/LAYER_PAST_T*
G04 Layer:  BOARD GEOMETRY/PANEL_OUTLINE*
G04 *
G04 Offset:    (0.00 0.00)*
G04 Mirror:    No*
G04 Mode:      Positive*
G04 Rotation:  0*
G04 FullContactRelief:  No*
G04 UndefLineWidth:     6.00*
G04 ================== end FILE IDENTIFICATION RECORD ====================*
%FSLAX35Y35*MOIN*%
%IR0*IPPOS*OFA0.00000B0.00000*MIA0B0*SFA1.00000B1.00000*%
%AMMACRO19*
4,1,40,.017,-.013,
.017,.013,
.016939,.013695,
.016759,.014368,
.016464,.015,
.016064,.015571,
.015571,.016064,
.015,.016464,
.014368,.016759,
.013695,.016939,
.013,.017,
-.013,.017,
-.013695,.016939,
-.014368,.016759,
-.015,.016464,
-.015571,.016064,
-.016064,.015571,
-.016464,.015,
-.016759,.014368,
-.016939,.013695,
-.017,.013,
-.017,-.013,
-.016939,-.013695,
-.016759,-.014368,
-.016464,-.015,
-.016064,-.015571,
-.015571,-.016064,
-.015,-.016464,
-.014368,-.016759,
-.013695,-.016939,
-.013,-.017,
.013,-.017,
.013695,-.016939,
.014368,-.016759,
.015,-.016464,
.015571,-.016064,
.016064,-.015571,
.016464,-.015,
.016759,-.014368,
.016939,-.013695,
.017,-.013,
0.0*
%
%ADD19MACRO19*%
%ADD27R,.11X.055*%
%ADD30R,.074X.122*%
%ADD10R,.05X.05*%
%AMMACRO25*
4,1,40,.007,.011,
-.007,.011,
-.007695,.010939,
-.008368,.010759,
-.009,.010464,
-.009571,.010064,
-.010064,.009571,
-.010464,.009,
-.010759,.008368,
-.010939,.007695,
-.011,.007,
-.011,-.007,
-.010939,-.007695,
-.010759,-.008368,
-.010464,-.009,
-.010064,-.009571,
-.009571,-.010064,
-.009,-.010464,
-.008368,-.010759,
-.007695,-.010939,
-.007,-.011,
.007,-.011,
.007695,-.010939,
.008368,-.010759,
.009,-.010464,
.009571,-.010064,
.010064,-.009571,
.010464,-.009,
.010759,-.008368,
.010939,-.007695,
.011,-.007,
.011,.007,
.010939,.007695,
.010759,.008368,
.010464,.009,
.010064,.009571,
.009571,.010064,
.009,.010464,
.008368,.010759,
.007695,.010939,
.007,.011,
0.0*
%
%ADD25MACRO25*%
%AMMACRO17*
4,1,40,.011,-.007,
.011,.007,
.010939,.007695,
.010759,.008368,
.010464,.009,
.010064,.009571,
.009571,.010064,
.009,.010464,
.008368,.010759,
.007695,.010939,
.007,.011,
-.007,.011,
-.007695,.010939,
-.008368,.010759,
-.009,.010464,
-.009571,.010064,
-.010064,.009571,
-.010464,.009,
-.010759,.008368,
-.010939,.007695,
-.011,.007,
-.011,-.007,
-.010939,-.007695,
-.010759,-.008368,
-.010464,-.009,
-.010064,-.009571,
-.009571,-.010064,
-.009,-.010464,
-.008368,-.010759,
-.007695,-.010939,
-.007,-.011,
.007,-.011,
.007695,-.010939,
.008368,-.010759,
.009,-.010464,
.009571,-.010064,
.010064,-.009571,
.010464,-.009,
.010759,-.008368,
.010939,-.007695,
.011,-.007,
0.0*
%
%ADD17MACRO17*%
%AMMACRO20*
4,1,40,-.017,.013,
-.017,-.013,
-.016939,-.013695,
-.016759,-.014368,
-.016464,-.015,
-.016064,-.015571,
-.015571,-.016064,
-.015,-.016464,
-.014368,-.016759,
-.013695,-.016939,
-.013,-.017,
.013,-.017,
.013695,-.016939,
.014368,-.016759,
.015,-.016464,
.015571,-.016064,
.016064,-.015571,
.016464,-.015,
.016759,-.014368,
.016939,-.013695,
.017,-.013,
.017,.013,
.016939,.013695,
.016759,.014368,
.016464,.015,
.016064,.015571,
.015571,.016064,
.015,.016464,
.014368,.016759,
.013695,.016939,
.013,.017,
-.013,.017,
-.013695,.016939,
-.014368,.016759,
-.015,.016464,
-.015571,.016064,
-.016064,.015571,
-.016464,.015,
-.016759,.014368,
-.016939,.013695,
-.017,.013,
0.0*
%
%ADD20MACRO20*%
%AMMACRO26*
4,1,40,.007,.011,
-.007,.011,
-.007695,.010939,
-.008368,.010759,
-.009,.010464,
-.009571,.010064,
-.010064,.009571,
-.010464,.009,
-.010759,.008368,
-.010939,.007695,
-.011,.007,
-.011,-.007,
-.010939,-.007695,
-.010759,-.008368,
-.010464,-.009,
-.010064,-.009571,
-.009571,-.010064,
-.009,-.010464,
-.008368,-.010759,
-.007695,-.010939,
-.007,-.011,
.007,-.011,
.007695,-.010939,
.008368,-.010759,
.009,-.010464,
.009571,-.010064,
.010064,-.009571,
.010464,-.009,
.010759,-.008368,
.010939,-.007695,
.011,-.007,
.011,.007,
.010939,.007695,
.010759,.008368,
.010464,.009,
.010064,.009571,
.009571,.010064,
.009,.010464,
.008368,.010759,
.007695,.010939,
.007,.011,
0.0*
%
%ADD26MACRO26*%
%AMMACRO18*
4,1,40,.011,-.007,
.011,.007,
.010939,.007695,
.010759,.008368,
.010464,.009,
.010064,.009571,
.009571,.010064,
.009,.010464,
.008368,.010759,
.007695,.010939,
.007,.011,
-.007,.011,
-.007695,.010939,
-.008368,.010759,
-.009,.010464,
-.009571,.010064,
-.010064,.009571,
-.010464,.009,
-.010759,.008368,
-.010939,.007695,
-.011,.007,
-.011,-.007,
-.010939,-.007695,
-.010759,-.008368,
-.010464,-.009,
-.010064,-.009571,
-.009571,-.010064,
-.009,-.010464,
-.008368,-.010759,
-.007695,-.010939,
-.007,-.011,
.007,-.011,
.007695,-.010939,
.008368,-.010759,
.009,-.010464,
.009571,-.010064,
.010064,-.009571,
.010464,-.009,
.010759,-.008368,
.010939,-.007695,
.011,-.007,
0.0*
%
%ADD18MACRO18*%
%AMMACRO21*
4,1,40,-.017,.013,
-.017,-.013,
-.016939,-.013695,
-.016759,-.014368,
-.016464,-.015,
-.016064,-.015571,
-.015571,-.016064,
-.015,-.016464,
-.014368,-.016759,
-.013695,-.016939,
-.013,-.017,
.013,-.017,
.013695,-.016939,
.014368,-.016759,
.015,-.016464,
.015571,-.016064,
.016064,-.015571,
.016464,-.015,
.016759,-.014368,
.016939,-.013695,
.017,-.013,
.017,.013,
.016939,.013695,
.016759,.014368,
.016464,.015,
.016064,.015571,
.015571,.016064,
.015,.016464,
.014368,.016759,
.013695,.016939,
.013,.017,
-.013,.017,
-.013695,.016939,
-.014368,.016759,
-.015,.016464,
-.015571,.016064,
-.016064,.015571,
-.016464,.015,
-.016759,.014368,
-.016939,.013695,
-.017,.013,
0.0*
%
%ADD21MACRO21*%
%ADD12R,.016X.06*%
%ADD11R,.055X.045*%
%AMMACRO29*
4,1,40,.007,.0225,
.008389,.022378,
.009736,.022018,
.011,.021428,
.012142,.020628,
.013128,.019642,
.013928,.0185,
.014518,.017236,
.014878,.015889,
.015,.0145,
.015,-.0145,
.014878,-.015889,
.014518,-.017236,
.013928,-.0185,
.013128,-.019642,
.012142,-.020628,
.011,-.021428,
.009736,-.022018,
.008389,-.022378,
.007,-.0225,
-.007,-.0225,
-.008389,-.022378,
-.009736,-.022018,
-.011,-.021428,
-.012142,-.020628,
-.013128,-.019642,
-.013928,-.0185,
-.014518,-.017236,
-.014878,-.015889,
-.015,-.0145,
-.015,.0145,
-.014878,.015889,
-.014518,.017236,
-.013928,.0185,
-.013128,.019642,
-.012142,.020628,
-.011,.021428,
-.009736,.022018,
-.008389,.022378,
-.007,.0225,
.007,.0225,
0.0*
%
%ADD29MACRO29*%
%ADD28R,.095X.09*%
%AMMACRO24*
4,1,40,-.008,-.012,
.008,-.012,
.008695,-.011939,
.009368,-.011759,
.01,-.011464,
.010571,-.011064,
.011064,-.010571,
.011464,-.01,
.011759,-.009368,
.011939,-.008695,
.012,-.008,
.012,.008,
.011939,.008695,
.011759,.009368,
.011464,.01,
.011064,.010571,
.010571,.011064,
.01,.011464,
.009368,.011759,
.008695,.011939,
.008,.012,
-.008,.012,
-.008695,.011939,
-.009368,.011759,
-.01,.011464,
-.010571,.011064,
-.011064,.010571,
-.011464,.01,
-.011759,.009368,
-.011939,.008695,
-.012,.008,
-.012,-.008,
-.011939,-.008695,
-.011759,-.009368,
-.011464,-.01,
-.011064,-.010571,
-.010571,-.011064,
-.01,-.011464,
-.009368,-.011759,
-.008695,-.011939,
-.008,-.012,
0.0*
%
%ADD24MACRO24*%
%AMMACRO13*
4,1,40,-.007,-.011,
.007,-.011,
.007695,-.010939,
.008368,-.010759,
.009,-.010464,
.009571,-.010064,
.010064,-.009571,
.010464,-.009,
.010759,-.008368,
.010939,-.007695,
.011,-.007,
.011,.007,
.010939,.007695,
.010759,.008368,
.010464,.009,
.010064,.009571,
.009571,.010064,
.009,.010464,
.008368,.010759,
.007695,.010939,
.007,.011,
-.007,.011,
-.007695,.010939,
-.008368,.010759,
-.009,.010464,
-.009571,.010064,
-.010064,.009571,
-.010464,.009,
-.010759,.008368,
-.010939,.007695,
-.011,.007,
-.011,-.007,
-.010939,-.007695,
-.010759,-.008368,
-.010464,-.009,
-.010064,-.009571,
-.009571,-.010064,
-.009,-.010464,
-.008368,-.010759,
-.007695,-.010939,
-.007,-.011,
0.0*
%
%ADD13MACRO13*%
%AMMACRO15*
4,1,40,-.011,.007,
-.011,-.007,
-.010939,-.007695,
-.010759,-.008368,
-.010464,-.009,
-.010064,-.009571,
-.009571,-.010064,
-.009,-.010464,
-.008368,-.010759,
-.007695,-.010939,
-.007,-.011,
.007,-.011,
.007695,-.010939,
.008368,-.010759,
.009,-.010464,
.009571,-.010064,
.010064,-.009571,
.010464,-.009,
.010759,-.008368,
.010939,-.007695,
.011,-.007,
.011,.007,
.010939,.007695,
.010759,.008368,
.010464,.009,
.010064,.009571,
.009571,.010064,
.009,.010464,
.008368,.010759,
.007695,.010939,
.007,.011,
-.007,.011,
-.007695,.010939,
-.008368,.010759,
-.009,.010464,
-.009571,.010064,
-.010064,.009571,
-.010464,.009,
-.010759,.008368,
-.010939,.007695,
-.011,.007,
0.0*
%
%ADD15MACRO15*%
%AMMACRO22*
4,1,40,.017,-.013,
.017,.013,
.016939,.013695,
.016759,.014368,
.016464,.015,
.016064,.015571,
.015571,.016064,
.015,.016464,
.014368,.016759,
.013695,.016939,
.013,.017,
-.013,.017,
-.013695,.016939,
-.014368,.016759,
-.015,.016464,
-.015571,.016064,
-.016064,.015571,
-.016464,.015,
-.016759,.014368,
-.016939,.013695,
-.017,.013,
-.017,-.013,
-.016939,-.013695,
-.016759,-.014368,
-.016464,-.015,
-.016064,-.015571,
-.015571,-.016064,
-.015,-.016464,
-.014368,-.016759,
-.013695,-.016939,
-.013,-.017,
.013,-.017,
.013695,-.016939,
.014368,-.016759,
.015,-.016464,
.015571,-.016064,
.016064,-.015571,
.016464,-.015,
.016759,-.014368,
.016939,-.013695,
.017,-.013,
0.0*
%
%ADD22MACRO22*%
%AMMACRO23*
4,1,40,-.008,-.012,
.008,-.012,
.008695,-.011939,
.009368,-.011759,
.01,-.011464,
.010571,-.011064,
.011064,-.010571,
.011464,-.01,
.011759,-.009368,
.011939,-.008695,
.012,-.008,
.012,.008,
.011939,.008695,
.011759,.009368,
.011464,.01,
.011064,.010571,
.010571,.011064,
.01,.011464,
.009368,.011759,
.008695,.011939,
.008,.012,
-.008,.012,
-.008695,.011939,
-.009368,.011759,
-.01,.011464,
-.010571,.011064,
-.011064,.010571,
-.011464,.01,
-.011759,.009368,
-.011939,.008695,
-.012,.008,
-.012,-.008,
-.011939,-.008695,
-.011759,-.009368,
-.011464,-.01,
-.011064,-.010571,
-.010571,-.011064,
-.01,-.011464,
-.009368,-.011759,
-.008695,-.011939,
-.008,-.012,
0.0*
%
%ADD23MACRO23*%
%AMMACRO14*
4,1,40,-.007,-.011,
.007,-.011,
.007695,-.010939,
.008368,-.010759,
.009,-.010464,
.009571,-.010064,
.010064,-.009571,
.010464,-.009,
.010759,-.008368,
.010939,-.007695,
.011,-.007,
.011,.007,
.010939,.007695,
.010759,.008368,
.010464,.009,
.010064,.009571,
.009571,.010064,
.009,.010464,
.008368,.010759,
.007695,.010939,
.007,.011,
-.007,.011,
-.007695,.010939,
-.008368,.010759,
-.009,.010464,
-.009571,.010064,
-.010064,.009571,
-.010464,.009,
-.010759,.008368,
-.010939,.007695,
-.011,.007,
-.011,-.007,
-.010939,-.007695,
-.010759,-.008368,
-.010464,-.009,
-.010064,-.009571,
-.009571,-.010064,
-.009,-.010464,
-.008368,-.010759,
-.007695,-.010939,
-.007,-.011,
0.0*
%
%ADD14MACRO14*%
%AMMACRO16*
4,1,40,-.011,.007,
-.011,-.007,
-.010939,-.007695,
-.010759,-.008368,
-.010464,-.009,
-.010064,-.009571,
-.009571,-.010064,
-.009,-.010464,
-.008368,-.010759,
-.007695,-.010939,
-.007,-.011,
.007,-.011,
.007695,-.010939,
.008368,-.010759,
.009,-.010464,
.009571,-.010064,
.010064,-.009571,
.010464,-.009,
.010759,-.008368,
.010939,-.007695,
.011,-.007,
.011,.007,
.010939,.007695,
.010759,.008368,
.010464,.009,
.010064,.009571,
.009571,.010064,
.009,.010464,
.008368,.010759,
.007695,.010939,
.007,.011,
-.007,.011,
-.007695,.010939,
-.008368,.010759,
-.009,.010464,
-.009571,.010064,
-.010064,.009571,
-.010464,.009,
-.010759,.008368,
-.010939,.007695,
-.011,.007,
0.0*
%
%ADD16MACRO16*%
%ADD31C,.02*%
%ADD32C,.006*%
G75*
%LPD*%
G75*
G54D10*
X-23622Y62794D03*
Y916269D03*
X1297695Y58466D03*
G54D11*
X197Y189819D03*
Y197419D03*
X9297Y189819D03*
Y197419D03*
X472898Y182636D03*
Y190236D03*
X550498Y322336D03*
Y329936D03*
G54D20*
X38109Y363133D03*
X542500Y258171D03*
X618000Y71700D03*
X612798Y403036D03*
X617798Y403136D03*
G54D12*
X49902Y379652D03*
X52462D03*
X55022D03*
X57582D03*
Y363352D03*
X55022D03*
X52462D03*
X49902D03*
G54D21*
X38109Y368733D03*
X542500Y263771D03*
X618000Y77300D03*
X612798Y408636D03*
X617798Y408736D03*
G54D30*
X618566Y343800D03*
X607104D03*
Y387500D03*
X618566D03*
G54D31*
G01X-4246Y-109426D02*
Y-189426D01*
G01D02*
X1290354D01*
G01X-4246Y-144926D02*
X1290354D01*
G01X-8246Y-93426D02*
G02I-12000J0D01*
G01X-13396D02*
G02I-6850J0D01*
G01X-20246Y-109426D02*
Y-77426D01*
G01X-4246Y-93426D02*
X-36246D01*
G01X-4246Y-109426D02*
X1290354D01*
G01X502854D02*
Y-189426D01*
G01X640354Y-109426D02*
Y-189426D01*
G01X755354Y-109426D02*
Y-189426D01*
G01X922854Y-109426D02*
Y-189426D01*
G01X1092854Y-109426D02*
Y-189426D01*
G01X1290354Y-109426D02*
Y-189426D01*
G01X1318354Y-93426D02*
G02I-12000J0D01*
G01X1313204D02*
G02I-6850J0D01*
G01X1306354Y-109426D02*
Y-77426D01*
G01X1322354Y-93426D02*
X1290354D01*
G54D22*
X38128Y379932D03*
X45807Y393668D03*
X542500Y274771D03*
X634488Y77603D03*
G54D13*
X33508Y374132D03*
Y368932D03*
X38598Y337936D03*
Y333436D03*
X69550Y378236D03*
X69547Y373979D03*
X69498Y369470D03*
X537733Y263971D03*
Y268971D03*
X526200Y326000D03*
X533636Y326402D03*
X533536Y330602D03*
X533636Y322102D03*
G54D32*
G01X85820Y-19685D02*
X-29308D01*
G01X-43308Y-5685D02*
G03X-29308Y-19685I14000J0D01*
G01X0Y3937D02*
Y106969D01*
G01Y3937D02*
Y106969D01*
G01X636457Y0D02*
X3937D01*
G01X636457D02*
X3937D01*
G01X0Y3937D02*
G03X3937Y0I3937J0D01*
G01X0Y3937D02*
G03X3937Y0I3937J0D01*
G01X-43308Y-5685D02*
Y103032D01*
G01X-7874Y50259D02*
Y3937D01*
G01D02*
G03X3937Y-7874I11811J0D01*
G01D02*
X77283D01*
G01X-7874Y103032D02*
Y75456D01*
G01Y75460D02*
G03X0I3937J0D01*
G01Y50259D02*
G03X-7874I-3937J0D01*
G01X-43307Y286142D02*
Y116811D01*
G01D02*
X-37402Y110906D01*
G01X-41339Y114843D02*
X-37402Y110906D01*
G01D02*
X-3937D01*
G01X-37402D02*
X-3937D01*
G01X0Y106969D02*
G03X-3937Y110906I-3937J0D01*
G01X0Y106969D02*
G03X-3937Y110906I-3937J0D01*
G01X-43308Y103032D02*
X-7874D01*
G01X-43307Y360039D02*
Y300709D01*
G01X-37402Y292047D02*
X-41339Y288110D01*
G01X-37402Y292047D02*
X-43307Y286142D01*
G01Y300709D02*
X-37402Y294803D01*
G01X-41339Y298740D02*
X-37402Y294803D01*
G01X-12598Y292047D02*
X-37402D01*
G01D02*
X-1378D01*
G01X-12598D02*
X-1378D01*
G01X-37402Y294803D02*
X-1378D01*
G01X-37402D02*
X-1378D01*
G01Y292047D02*
G03Y294803I0J1378D01*
G01Y292047D02*
G03Y294803I0J1378D01*
G01X-37402Y365945D02*
X-41339Y362008D01*
G01X-37402Y365945D02*
X-43307Y360039D01*
G01X0Y369882D02*
Y468504D01*
G01Y369882D02*
Y468504D01*
G01X-3937Y365945D02*
X-37402D01*
G01X-3937D02*
X-37402D01*
G01X-3937D02*
G03X0Y369882I0J3937D01*
G01X-3937Y365945D02*
G03X0Y369882I0J3937D01*
G01X-7874Y401397D02*
Y373819D01*
G01D02*
X-43307D01*
G01D02*
X-43308Y373820D01*
G01D02*
Y583347D01*
G01X0Y401397D02*
G03X-7874I-3937J0D01*
G01Y426594D02*
G03X0I3937J0D01*
G01X-7874D02*
Y530574D01*
G01X3937Y472441D02*
X636457D01*
G01X3937D02*
X636457D01*
G01X3937D02*
G03X0Y468504I0J-3937D01*
G01X3937Y472441D02*
G03X0Y468504I0J-3937D01*
G01Y484252D02*
Y587283D01*
G01Y484252D02*
Y587283D01*
G01X636457Y480315D02*
X3937D01*
G01X636457D02*
X3937D01*
G01X0Y484252D02*
G03X3937Y480315I3937J0D01*
G01X0Y484252D02*
G03X3937Y480315I3937J0D01*
G01X-7874Y583347D02*
Y555771D01*
G01D02*
G03X0I3937J0D01*
G01Y530574D02*
G03X-7874I-3937J0D01*
G01X-43307Y766457D02*
Y597126D01*
G01D02*
X-37402Y591220D01*
G01X-41339Y595157D02*
X-37402Y591220D01*
G01D02*
X-3937D01*
G01X-37402D02*
X-3937D01*
G01X0Y587283D02*
G03X-3937Y591220I-3937J0D01*
G01X0Y587283D02*
G03X-3937Y591220I-3937J0D01*
G01X-43308Y583347D02*
X-7874D01*
G01X-43307Y840354D02*
Y781024D01*
G01X-37402Y772362D02*
X-41339Y768425D01*
G01X-37402Y772362D02*
X-43307Y766457D01*
G01Y781024D02*
X-37402Y775118D01*
G01X-41339Y779055D02*
X-37402Y775118D01*
G01X-12598Y772362D02*
X-37402D01*
G01D02*
X-1378D01*
G01X-12598D02*
X-1378D01*
G01X-37402Y775118D02*
X-1378D01*
G01X-37402D02*
X-1378D01*
G01Y772362D02*
G03Y775118I0J1378D01*
G01Y772362D02*
G03Y775118I0J1378D01*
G01X-37402Y846260D02*
X-41339Y842323D01*
G01X-37402Y846260D02*
X-43307Y840354D01*
G01X0Y850197D02*
Y948819D01*
G01Y850197D02*
Y948819D01*
G01X-3937Y846260D02*
X-37402D01*
G01X-3937D02*
X-37402D01*
G01X-3937D02*
G03X0Y850197I0J3937D01*
G01X-3937Y846260D02*
G03X0Y850197I0J3937D01*
G01X-7874Y881712D02*
Y854134D01*
G01D02*
X-43308D01*
G01D02*
Y958441D01*
G01X0Y881711D02*
G03X-7874I-3937J0D01*
G01X3937Y952756D02*
X636457D01*
G01X3937D02*
X636457D01*
G01X3937D02*
G03X0Y948819I0J-3937D01*
G01X3937Y952756D02*
G03X0Y948819I0J-3937D01*
G01X-29308Y972441D02*
G03X-43308Y958441I0J-14000D01*
G01X-7874Y906909D02*
G03X0I3937J0D01*
G01X-7874D02*
Y948819D01*
G01X3937Y960630D02*
G03X-7874Y948819I0J-11811D01*
G01X-29308Y972441D02*
X1317968D01*
G01X3937Y960630D02*
X77283D01*
G01X16751Y-179426D02*
Y-161926D01*
G01X25047D02*
X16751Y-172718D01*
G01X26357Y-179426D02*
X20462Y-167760D01*
G01X34032Y-179426D02*
Y-161926D01*
X44076Y-179426D01*
Y-161926D01*
G01X56554Y-179426D02*
X54807Y-179134D01*
X53279Y-177968D01*
X51969Y-176218D01*
X51095Y-174176D01*
X50659Y-171843D01*
Y-169509D01*
X51095Y-167176D01*
X51969Y-165134D01*
X53279Y-163385D01*
X54807Y-162218D01*
X56554Y-161926D01*
X58300Y-162218D01*
X59829Y-163385D01*
X61139Y-165134D01*
X62013Y-167176D01*
X62449Y-169509D01*
Y-171843D01*
X62013Y-174176D01*
X61139Y-176218D01*
X59829Y-177968D01*
X58300Y-179134D01*
X56554Y-179426D01*
G01X69469D02*
X78639Y-161926D01*
G01X69469D02*
X78639Y-179426D01*
G01X104687D02*
Y-161926D01*
X109927D01*
X111674Y-162801D01*
X112984Y-164843D01*
X113421Y-167176D01*
X112984Y-169509D01*
X111892Y-171259D01*
X109927Y-172135D01*
X104687D01*
G01X126554Y-179426D02*
X124807Y-179134D01*
X123279Y-177968D01*
X121969Y-176218D01*
X121095Y-174176D01*
X120659Y-171843D01*
Y-169509D01*
X121095Y-167176D01*
X121969Y-165134D01*
X123279Y-163385D01*
X124807Y-162218D01*
X126554Y-161926D01*
X128300Y-162218D01*
X129829Y-163385D01*
X131139Y-165134D01*
X132013Y-167176D01*
X132449Y-169509D01*
Y-171843D01*
X132013Y-174176D01*
X131139Y-176218D01*
X129829Y-177968D01*
X128300Y-179134D01*
X126554Y-179426D01*
G01X137504Y-161926D02*
X140560Y-179426D01*
X144054Y-161926D01*
X147547Y-179426D01*
X150604Y-161926D01*
G01X165921Y-179426D02*
X157187D01*
Y-161926D01*
X165921D01*
G01X162427Y-170384D02*
X157187D01*
G01X174687Y-179426D02*
Y-161926D01*
X180146D01*
X181892Y-162801D01*
X182984Y-163968D01*
X183421Y-166301D01*
X182984Y-168635D01*
X181674Y-170093D01*
X180146Y-170968D01*
X174687D01*
G01X180146D02*
X183421Y-179426D01*
G01X214054Y-161926D02*
Y-179426D01*
G01X209032Y-161926D02*
X219076D01*
G01X227187Y-179426D02*
Y-161926D01*
X232646D01*
X234392Y-162801D01*
X235484Y-163968D01*
X235921Y-166301D01*
X235484Y-168635D01*
X234174Y-170093D01*
X232646Y-170968D01*
X227187D01*
G01X232646D02*
X235921Y-179426D01*
G01X243595D02*
X249054Y-161926D01*
X254513Y-179426D01*
G01X252547Y-173301D02*
X245560D01*
G01X261532Y-179426D02*
Y-161926D01*
X271576Y-179426D01*
Y-161926D01*
G01X279469Y-177093D02*
X281216Y-178551D01*
X283181Y-179426D01*
X284927D01*
X286674Y-178551D01*
X287984Y-177093D01*
X288639Y-175051D01*
X288202Y-173010D01*
X287111Y-171259D01*
X285146Y-170093D01*
X282526Y-169509D01*
X280997Y-168343D01*
X280342Y-166301D01*
X280779Y-164259D01*
X281871Y-162801D01*
X283399Y-161926D01*
X284927D01*
X286456Y-162509D01*
X287766Y-163968D01*
G01X298934Y-161926D02*
X304174D01*
G01X301554D02*
Y-179426D01*
G01X298934D02*
X304174D01*
G01X319054Y-161926D02*
Y-179426D01*
G01X314032Y-161926D02*
X324076D01*
G01X333934D02*
X339174D01*
G01X336554D02*
Y-179426D01*
G01X333934D02*
X339174D01*
G01X354054D02*
X352307Y-179134D01*
X350779Y-177968D01*
X349469Y-176218D01*
X348595Y-174176D01*
X348159Y-171843D01*
Y-169509D01*
X348595Y-167176D01*
X349469Y-165134D01*
X350779Y-163385D01*
X352307Y-162218D01*
X354054Y-161926D01*
X355800Y-162218D01*
X357329Y-163385D01*
X358639Y-165134D01*
X359513Y-167176D01*
X359949Y-169509D01*
Y-171843D01*
X359513Y-174176D01*
X358639Y-176218D01*
X357329Y-177968D01*
X355800Y-179134D01*
X354054Y-179426D01*
G01X366532D02*
Y-161926D01*
X376576Y-179426D01*
Y-161926D01*
G01X408300Y-170093D02*
X409174Y-169218D01*
X409829Y-167760D01*
X410266Y-165717D01*
X409829Y-163968D01*
X408956Y-162801D01*
X407427Y-161926D01*
X401532D01*
Y-179426D01*
X408737D01*
X410266Y-178260D01*
X411139Y-176509D01*
X411576Y-174468D01*
X411139Y-172426D01*
X409829Y-170676D01*
X408300Y-170093D01*
X401532D01*
G01X424054Y-179426D02*
X422307Y-179134D01*
X420779Y-177968D01*
X419469Y-176218D01*
X418595Y-174176D01*
X418159Y-171843D01*
Y-169509D01*
X418595Y-167176D01*
X419469Y-165134D01*
X420779Y-163385D01*
X422307Y-162218D01*
X424054Y-161926D01*
X425800Y-162218D01*
X427329Y-163385D01*
X428639Y-165134D01*
X429513Y-167176D01*
X429949Y-169509D01*
Y-171843D01*
X429513Y-174176D01*
X428639Y-176218D01*
X427329Y-177968D01*
X425800Y-179134D01*
X424054Y-179426D01*
G01X436095D02*
X441554Y-161926D01*
X447013Y-179426D01*
G01X445047Y-173301D02*
X438060D01*
G01X454687Y-179426D02*
Y-161926D01*
X460146D01*
X461892Y-162801D01*
X462984Y-163968D01*
X463421Y-166301D01*
X462984Y-168635D01*
X461674Y-170093D01*
X460146Y-170968D01*
X454687D01*
G01X460146D02*
X463421Y-179426D01*
G01X471751D02*
Y-161926D01*
X476117D01*
X477864Y-162801D01*
X479174Y-163968D01*
X480266Y-165717D01*
X481139Y-167760D01*
X481357Y-170676D01*
X481139Y-173593D01*
X480266Y-175635D01*
X479174Y-177385D01*
X477864Y-178551D01*
X476117Y-179426D01*
X471751D01*
G01X17244Y226378D02*
Y246063D01*
G01X29055D02*
Y226378D01*
G01X25118Y222441D02*
X21181D01*
G01Y250000D02*
X25118D01*
G01X17244Y226378D02*
G03X21181Y222441I3937J0D01*
G01X25118D02*
G03X29055Y226378I0J3937D01*
G01Y246063D02*
G03X25118Y250000I-3937J0D01*
G01X21181D02*
G03X17244Y246063I0J-3937D01*
G01Y706693D02*
Y726378D01*
G01X29055D02*
Y706693D01*
G01X25118Y702756D02*
X21181D01*
G01Y730315D02*
X25118D01*
G01X17244Y706693D02*
G03X21181Y702756I3937J0D01*
G01X25118D02*
G03X29055Y706693I0J3937D01*
G01Y726378D02*
G03X25118Y730315I-3937J0D01*
G01X21181D02*
G03X17244Y726378I0J-3937D01*
G01X93694Y-19685D02*
X1317968D01*
G01X93694D02*
G03X85820I-3937J0D01*
G01X107993Y-7874D02*
X304843D01*
G01X107993Y0D02*
G03Y-7874I0J-3937D01*
G01X77283D02*
G03Y0I0J3937D01*
G01X107993Y480315D02*
G03Y472441I0J-3937D01*
G01X77283D02*
G03Y480315I0J3937D01*
G01X107993Y960630D02*
G03Y952756I0J-3937D01*
G01X77283D02*
G03Y960630I0J3937D01*
G01X107993D02*
X304843D01*
G01X208377Y-134426D02*
Y-116926D01*
X214054Y-131509D01*
X219731Y-116926D01*
Y-134426D01*
G01X231554D02*
X230244Y-134134D01*
X228934Y-132968D01*
X228060Y-130926D01*
X227624Y-128593D01*
X228060Y-126259D01*
X228934Y-124218D01*
X230244Y-123051D01*
X231554Y-122760D01*
X232864Y-123051D01*
X234174Y-124218D01*
X235047Y-126259D01*
X235266Y-128593D01*
X235047Y-130926D01*
X234174Y-132968D01*
X232864Y-134134D01*
X231554Y-134426D01*
G01X252984Y-116926D02*
Y-134426D01*
G01Y-131802D02*
X252111Y-133260D01*
X250800Y-134134D01*
X249272Y-134426D01*
X247526Y-133843D01*
X246216Y-132385D01*
X245342Y-130635D01*
X245124Y-128593D01*
X245342Y-126551D01*
X246216Y-124801D01*
X247526Y-123343D01*
X249272Y-122760D01*
X250800Y-123051D01*
X251892Y-123635D01*
X252984Y-124801D01*
G01X263279Y-126551D02*
X270266D01*
X269611Y-124509D01*
X268519Y-123343D01*
X266991Y-122760D01*
X265462Y-123051D01*
X264152Y-123926D01*
X263279Y-125968D01*
X262842Y-127718D01*
Y-129468D01*
X263279Y-131218D01*
X264371Y-132968D01*
X265681Y-134134D01*
X267209Y-134426D01*
X268737Y-133843D01*
X270266Y-132093D01*
G01X284054Y-134426D02*
Y-116926D01*
G01X335552Y-7874D02*
X532402D01*
G01X304843D02*
G03Y0I0J3937D01*
G01X335552D02*
G03Y-7874I0J-3937D01*
G01Y480315D02*
G03Y472441I0J-3937D01*
G01X304843D02*
G03Y480315I0J3937D01*
G01Y952756D02*
G03Y960630I0J3937D01*
G01X335552D02*
G03Y952756I0J-3937D01*
G01Y960630D02*
X532402D01*
G01X536554Y-179426D02*
Y-161926D01*
X533934Y-165426D01*
G01Y-179426D02*
X539174D01*
G01X549906Y-164843D02*
X551216Y-163093D01*
X552744Y-162218D01*
X554491Y-161926D01*
X556674Y-162509D01*
X558202Y-163968D01*
X558639Y-165717D01*
X558421Y-167468D01*
X557547Y-168926D01*
X553181Y-171843D01*
X551216Y-173884D01*
X549906Y-176802D01*
X549469Y-179426D01*
X558639D01*
G01X566751Y-176802D02*
X568060Y-178260D01*
X569589Y-179134D01*
X571554Y-179426D01*
X573519Y-178843D01*
X575047Y-177676D01*
X576139Y-175635D01*
X576357Y-173301D01*
X575921Y-170968D01*
X574829Y-169509D01*
X573300Y-168343D01*
X571772Y-168051D01*
X570244Y-168343D01*
X568279Y-169509D01*
X568934Y-161926D01*
X574829D01*
G01X584906Y-164843D02*
X586216Y-163093D01*
X587744Y-162218D01*
X589491Y-161926D01*
X591674Y-162509D01*
X593202Y-163968D01*
X593639Y-165717D01*
X593421Y-167468D01*
X592547Y-168926D01*
X588181Y-171843D01*
X586216Y-173884D01*
X584906Y-176802D01*
X584469Y-179426D01*
X593639D01*
G01X601751Y-175926D02*
X603060Y-177968D01*
X604807Y-179134D01*
X606772Y-179426D01*
X608519Y-179134D01*
X610266Y-177676D01*
X611357Y-175926D01*
X611576Y-174176D01*
X611139Y-172135D01*
X609611Y-170676D01*
X608082Y-170093D01*
X606117D01*
G01X608082D02*
X609392Y-169218D01*
X610484Y-167760D01*
X610921Y-166010D01*
X610484Y-164259D01*
X609392Y-162801D01*
X607427Y-161926D01*
X605462Y-162218D01*
X603497Y-163385D01*
G01X523437Y-134426D02*
Y-116926D01*
X528677D01*
X530424Y-117801D01*
X531734Y-119843D01*
X532171Y-122176D01*
X531734Y-124509D01*
X530642Y-126259D01*
X528677Y-127135D01*
X523437D01*
G01X550107Y-118385D02*
X548797Y-117509D01*
X547269Y-116926D01*
X545522D01*
X543557Y-117801D01*
X542029Y-119259D01*
X540937Y-121010D01*
X540064Y-123926D01*
X539845Y-126551D01*
X540282Y-129176D01*
X540937Y-130926D01*
X542247Y-132676D01*
X543776Y-133843D01*
X545304Y-134426D01*
X546832D01*
X548361Y-133843D01*
X549671Y-132968D01*
X550763Y-131802D01*
G01X564550Y-125093D02*
X565424Y-124218D01*
X566079Y-122760D01*
X566516Y-120717D01*
X566079Y-118968D01*
X565206Y-117801D01*
X563677Y-116926D01*
X557782D01*
Y-134426D01*
X564987D01*
X566516Y-133260D01*
X567389Y-131509D01*
X567826Y-129468D01*
X567389Y-127426D01*
X566079Y-125676D01*
X564550Y-125093D01*
X557782D01*
G01X573754Y-140259D02*
X586854D01*
G01X592782Y-134426D02*
Y-116926D01*
X602826Y-134426D01*
Y-116926D01*
G01X615304Y-134426D02*
X613557Y-134134D01*
X612029Y-132968D01*
X610719Y-131218D01*
X609845Y-129176D01*
X609409Y-126843D01*
Y-124509D01*
X609845Y-122176D01*
X610719Y-120134D01*
X612029Y-118385D01*
X613557Y-117218D01*
X615304Y-116926D01*
X617050Y-117218D01*
X618579Y-118385D01*
X619889Y-120134D01*
X620763Y-122176D01*
X621199Y-124509D01*
Y-126843D01*
X620763Y-129176D01*
X619889Y-131218D01*
X618579Y-132968D01*
X617050Y-134134D01*
X615304Y-134426D01*
G01X563111Y-7874D02*
X725552D01*
G01X563111Y0D02*
G03Y-7874I0J-3937D01*
G01X532402D02*
G03Y0I0J3937D01*
G01X627391Y353740D02*
X545906D01*
G01X627391D02*
X545906D01*
G01X627391Y378543D02*
X545906D01*
G01X627391D02*
X545906D01*
G01X541969Y357677D02*
Y374606D01*
G01Y357677D02*
Y374606D01*
G01X545906Y378543D02*
G03X541969Y374606I0J-3937D01*
G01Y357677D02*
G03X545906Y353740I3937J0D01*
G01X541969Y357677D02*
G03X545906Y353740I3937J0D01*
G01Y378543D02*
G03X541969Y374606I0J-3937D01*
G01X563111Y480315D02*
G03Y472441I0J-3937D01*
G01X532402D02*
G03Y480315I0J3937D01*
G01X627391Y834055D02*
X545906D01*
G01X627391D02*
X545906D01*
G01X541969Y837992D02*
Y854921D01*
G01Y837992D02*
Y854921D01*
G01Y837992D02*
G03X545906Y834055I3937J0D01*
G01X541969Y837992D02*
G03X545906Y834055I3937J0D01*
G01X627391Y858858D02*
X545906D01*
G01X627391D02*
X545906D01*
G01D02*
G03X541969Y854921I0J-3937D01*
G01X545906Y858858D02*
G03X541969Y854921I0J-3937D01*
G01X563111Y960630D02*
G03Y952756I0J-3937D01*
G01X532402D02*
G03Y960630I0J3937D01*
G01X563111D02*
X725552D01*
G01X636457Y132035D02*
X624646D01*
G01X636457D02*
X624646D01*
G01X620709Y135972D02*
Y312846D01*
G01Y135972D02*
Y312846D01*
G01Y135972D02*
G03X622708Y132545I3937J0D01*
G01X620709Y135972D02*
G03X622675Y132564I3937J0D01*
G01X622708Y132545D02*
G03X624646Y132035I1938J3427D01*
G01X622675Y132564D02*
G03X624646Y132035I1971J3409D01*
G01X620709Y135972D02*
Y312846D01*
G01Y135972D02*
Y312846D01*
G01Y135972D02*
G03X622708Y132545I3937J0D01*
G01X620709Y135972D02*
G03X622675Y132564I3937J0D01*
G01D02*
G03X624646Y132035I1971J3409D01*
G01X620709Y312657D02*
Y311161D01*
G01X636457Y316783D02*
X624646D01*
G01X636457D02*
X624646D01*
G01X622708Y316274D02*
G03X620709Y312846I1938J-3427D01*
G01X622675Y316255D02*
G03X620709Y312846I1971J-3408D01*
G01X624646Y316783D02*
G03X622708Y316274I-2J-3937D01*
G01X624646Y316783D02*
G03X622675Y316255I-1J-3937D01*
G01X622708Y316274D02*
G03X620709Y312846I1938J-3427D01*
G01X622675Y316255D02*
G03X620709Y312846I1971J-3408D01*
G01X624646Y316783D02*
G03X622675Y316255I-1J-3937D01*
G01X629574Y379204D02*
X638641Y385248D01*
G01X629574Y379204D02*
X638641Y385248D01*
G01Y347035D02*
X629574Y353079D01*
G01X638641Y347035D02*
X629574Y353079D01*
G01D02*
G03X627391Y353740I-2183J-3276D01*
G01X629574Y353079D02*
G03X627391Y353740I-2183J-3276D01*
G01Y378543D02*
G03X629574Y379205I-2J3937D01*
G01X627391Y378543D02*
G03X629574Y379205I-2J3937D01*
G01X636457Y612350D02*
X624646D01*
G01X636457D02*
X624646D01*
G01X620709Y616287D02*
Y793161D01*
G01Y616287D02*
Y793161D01*
G01Y616287D02*
G03X622708Y612860I3937J0D01*
G01X620709Y616287D02*
G03X622675Y612879I3937J0D01*
G01X622708Y612860D02*
G03X624646Y612350I1938J3427D01*
G01X622675Y612879D02*
G03X624646Y612350I1971J3409D01*
G01X638641Y827350D02*
X629574Y833394D01*
G01X638641Y827350D02*
X629574Y833394D01*
G01D02*
G03X627391Y834055I-2184J-3276D01*
G01X629574Y833394D02*
G03X627391Y834055I-2184J-3276D01*
G01X636457Y797098D02*
X624646D01*
G01X636457D02*
X624646D01*
G01X622708Y796589D02*
G03X620709Y793161I1938J-3427D01*
G01X622675Y796570D02*
G03X620709Y793161I1971J-3408D01*
G01X624646Y797098D02*
G03X622708Y796589I-2J-3937D01*
G01X624646Y797098D02*
G03X622675Y796570I-1J-3937D01*
G01X629574Y859520D02*
X638641Y865563D01*
G01X629574Y859520D02*
X638641Y865563D01*
G01X627391Y858858D02*
G03X629574Y859520I-2J3937D01*
G01X627391Y858858D02*
G03X629574Y859520I-2J3937D01*
G01X697854Y-179426D02*
Y-161926D01*
X695234Y-165426D01*
G01Y-179426D02*
X700474D01*
G01X666145Y-116926D02*
X671604Y-134426D01*
X677063Y-116926D01*
G01X693471Y-134426D02*
X684737D01*
Y-116926D01*
X693471D01*
G01X689977Y-125384D02*
X684737D01*
G01X702237Y-134426D02*
Y-116926D01*
X707696D01*
X709442Y-117801D01*
X710534Y-118968D01*
X710971Y-121301D01*
X710534Y-123635D01*
X709224Y-125093D01*
X707696Y-125968D01*
X702237D01*
G01X707696D02*
X710971Y-134426D01*
G01X724104Y-135009D02*
X723667Y-134718D01*
Y-134134D01*
X724104Y-133843D01*
X724541Y-134134D01*
Y-134718D01*
X724104Y-135009D01*
G01X640394Y112350D02*
Y3937D01*
G01Y112350D02*
Y3937D01*
G01X636457Y0D02*
G03X640394Y3937I0J3937D01*
G01X636457Y0D02*
G03X640394Y3937I0J3937D01*
G01X1284723Y0D02*
X652203D01*
G01X1284723D02*
X652203D01*
G01X648266Y3937D02*
Y83917D01*
G01Y3937D02*
Y83917D01*
G01Y3937D02*
G03X652203Y0I3937J0D01*
G01X648266Y3937D02*
G03X652203Y0I3937J0D01*
G01X648267Y34437D02*
G03X640393I-3937J0D01*
G01X640394Y128098D02*
Y3937D01*
G01Y128098D02*
Y3937D01*
G01X659085Y93237D02*
X650019Y87193D01*
G01X659085Y93237D02*
X650019Y87193D01*
G01X661269Y93898D02*
X742754D01*
G01X661269D02*
X742754D01*
G01X650019Y87193D02*
G03X648266Y83917I2185J-3276D01*
G01X661269Y93898D02*
G03X659085Y93237I0J-3937D01*
G01X661269Y93898D02*
G03X659085Y93237I0J-3937D01*
G01X650019Y87193D02*
G03X648266Y83917I2185J-3276D01*
G01X640393Y65146D02*
G03X648267I3937J0D01*
G01X661269Y118701D02*
X742754D01*
G01X661269D02*
X742754D01*
G01X650019Y125406D02*
X659085Y119362D01*
G01X650019Y125406D02*
X659085Y119362D01*
G01D02*
G03X661269Y118701I2184J3276D01*
G01X648266Y128682D02*
G03X650019Y125406I3937J0D01*
G01X648266Y128682D02*
G03X650019Y125406I3937J0D01*
G01X659085Y119362D02*
G03X661269Y118701I2184J3276D01*
G01X640394Y128098D02*
G03X636457Y132035I-3937J0D01*
G01X640394Y128098D02*
G03X636457Y132035I-3937J0D01*
G01X652203Y155657D02*
X664014D01*
G01X652203D02*
X664014D01*
G01X667951Y336469D02*
Y159594D01*
G01Y336469D02*
Y159594D01*
G01X648266Y128682D02*
Y151720D01*
G01Y128682D02*
Y151720D01*
G01X665952Y156167D02*
G03X667951Y159594I-1938J3427D01*
G01X665985Y156186D02*
G03X667951Y159594I-1971J3408D01*
G01X664014Y155657D02*
G03X665952Y156167I0J3937D01*
G01X652203Y155657D02*
G03X648266Y151720I0J-3937D01*
G01X652203Y155657D02*
G03X648266Y151720I0J-3937D01*
G01X664014Y155657D02*
G03X665985Y156186I0J3938D01*
G01X640394Y343759D02*
Y320720D01*
G01Y343759D02*
Y320720D01*
G01X636457Y316783D02*
G03X640394Y320720I0J3937D01*
G01X636457Y316783D02*
G03X640394Y320720I0J3937D01*
G01Y468504D02*
Y388524D01*
G01Y468504D02*
Y388524D01*
G01Y343759D02*
G03X638641Y347035I-3938J0D01*
G01X640394Y343759D02*
G03X638641Y347035I-3938J0D01*
G01Y385248D02*
G03X640394Y388524I-2185J3276D01*
G01X638641Y385248D02*
G03X640394Y388524I-2185J3276D01*
G01X648266Y360091D02*
Y468504D01*
G01Y360091D02*
Y468504D01*
G01X652203Y340406D02*
X664014D01*
G01X652203D02*
X664014D01*
G01X648266Y344343D02*
Y468504D01*
G01Y344343D02*
Y468504D01*
G01X667951Y336469D02*
G03X665952Y339896I-3937J0D01*
G01X667951Y336469D02*
G03X665985Y339877I-3937J0D01*
G01X648266Y344343D02*
G03X652203Y340406I3937J0D01*
G01X665952Y339896D02*
G03X664014Y340406I-1938J-3427D01*
G01X648266Y344343D02*
G03X652203Y340406I3937J0D01*
G01X665985Y339877D02*
G03X664014Y340406I-1971J-3409D01*
G01X648267Y407295D02*
G03X640393I-3937J0D01*
G01Y438004D02*
G03X648267I3937J0D01*
G01X640394Y468504D02*
G03X636457Y472441I-3937J0D01*
G01X640394Y468504D02*
G03X636457Y472441I-3937J0D01*
G01X640394Y592665D02*
Y484252D01*
G01Y592665D02*
Y484252D01*
G01X636457Y480315D02*
G03X640394Y484252I0J3937D01*
G01X636457Y480315D02*
G03X640394Y484252I0J3937D01*
G01X1284723Y480315D02*
X652203D01*
G01X1284723D02*
X652203D01*
G01X648266Y484252D02*
Y564231D01*
G01Y484252D02*
Y564231D01*
G01Y484252D02*
G03X652203Y480315I3937J0D01*
G01X648266Y484252D02*
G03X652203Y480315I3937J0D01*
G01Y472441D02*
X1284723D01*
G01X652203D02*
X1284723D01*
G01X652203D02*
G03X648266Y468504I0J-3937D01*
G01X652203Y472441D02*
G03X648266Y468504I0J-3937D01*
G01X640394Y608413D02*
Y484252D01*
G01Y608413D02*
Y484252D01*
G01X640393Y545462D02*
G03X648267I3937J0D01*
G01Y514753D02*
G03X640393I-3937J0D01*
G01X659085Y573552D02*
X650019Y567507D01*
G01X659085Y573552D02*
X650019Y567507D01*
G01X661269Y599016D02*
X742754D01*
G01X661269D02*
X742754D01*
G01X661269Y574213D02*
X742754D01*
G01X661269D02*
X742754D01*
G01X650019Y605721D02*
X659085Y599677D01*
G01X650019Y605721D02*
X659085Y599677D01*
G01D02*
G03X661269Y599016I2184J3276D01*
G01X648266Y608997D02*
G03X650019Y605721I3937J0D01*
G01X648266Y608997D02*
G03X650019Y605721I3937J0D01*
G01X659085Y599677D02*
G03X661269Y599016I2184J3276D01*
G01X650019Y567507D02*
G03X648266Y564231I2184J-3276D01*
G01X661269Y574213D02*
G03X659085Y573552I0J-3937D01*
G01X661269Y574213D02*
G03X659085Y573552I0J-3937D01*
G01X650019Y567507D02*
G03X648266Y564231I2184J-3276D01*
G01X640394Y608413D02*
G03X636457Y612350I-3937J0D01*
G01X640394Y608413D02*
G03X636457Y612350I-3937J0D01*
G01X648266Y608997D02*
Y632035D01*
G01Y608997D02*
Y632035D01*
G01X652203Y635972D02*
X664014D01*
G01X652203D02*
X664014D01*
G01X667951Y816783D02*
Y639909D01*
G01Y816783D02*
Y639909D01*
G01X665952Y636482D02*
G03X667951Y639909I-1938J3427D01*
G01X665985Y636501D02*
G03X667951Y639909I-1971J3408D01*
G01X664014Y635972D02*
G03X665952Y636482I0J3937D01*
G01X652203Y635972D02*
G03X648266Y632035I0J-3937D01*
G01X652203Y635972D02*
G03X648266Y632035I0J-3937D01*
G01X664014Y635972D02*
G03X665985Y636501I0J3938D01*
G01X640394Y824074D02*
G03X638641Y827350I-3938J0D01*
G01X640394Y824074D02*
G03X638641Y827350I-3938J0D01*
G01X648266Y840406D02*
Y948819D01*
G01Y840406D02*
Y948819D01*
G01X640394Y824074D02*
Y801035D01*
G01Y824074D02*
Y801035D01*
G01X636457Y797098D02*
G03X640394Y801035I0J3937D01*
G01X636457Y797098D02*
G03X640394Y801035I0J3937D01*
G01X652203Y820720D02*
X664014D01*
G01X652203D02*
X664014D01*
G01X648266Y824657D02*
Y948819D01*
G01Y824657D02*
Y948819D01*
G01X667951Y816783D02*
G03X665952Y820211I-3937J1D01*
G01X667951Y816783D02*
G03X665985Y820192I-3937J1D01*
G01X648266Y824657D02*
G03X652203Y820720I3937J0D01*
G01X665952Y820211D02*
G03X664014Y820720I-1936J-3428D01*
G01X648266Y824657D02*
G03X652203Y820720I3937J0D01*
G01X665985Y820192D02*
G03X664014Y820720I-1970J-3409D01*
G01X640394Y948819D02*
Y868839D01*
G01Y948819D02*
Y868839D01*
G01X638641Y865563D02*
G03X640394Y868839I-2185J3276D01*
G01X638641Y865563D02*
G03X640394Y868839I-2185J3276D01*
G01X648267Y887611D02*
G03X640393I-3937J0D01*
G01X640394Y948819D02*
G03X636457Y952756I-3937J0D01*
G01X640394Y948819D02*
G03X636457Y952756I-3937J0D01*
G01X652203D02*
X1284723D01*
G01X652203D02*
X1284723D01*
G01X652203D02*
G03X648266Y948819I0J-3937D01*
G01X652203Y952756D02*
G03X648266Y948819I0J-3937D01*
G01X640393Y918320D02*
G03X648267I3937J0D01*
G01X725552Y-7874D02*
G03Y0I0J3937D01*
G01X746691Y114764D02*
Y97835D01*
G01Y114764D02*
Y97835D01*
G01X742754Y93898D02*
G03X746691Y97835I0J3937D01*
G01X742754Y93898D02*
G03X746691Y97835I0J3937D01*
G01Y114764D02*
G03X742754Y118701I-3937J0D01*
G01X746691Y114764D02*
G03X742754Y118701I-3937J0D01*
G01X725552Y472441D02*
G03Y480315I0J3937D01*
G01X746691Y595079D02*
Y578150D01*
G01Y595079D02*
Y578150D01*
G01X742754Y574213D02*
G03X746691Y578150I0J3937D01*
G01Y595079D02*
G03X742754Y599016I-3937J0D01*
G01X746691Y595079D02*
G03X742754Y599016I-3937J0D01*
G01Y574213D02*
G03X746691Y578150I0J3937D01*
G01X725552Y952756D02*
G03Y960630I0J3937D01*
G01X790937Y-116926D02*
Y-134426D01*
X799671D01*
G01X816734D02*
Y-122760D01*
G01Y-124801D02*
X815861Y-123635D01*
X814550Y-123051D01*
X813022Y-122760D01*
X811494Y-123343D01*
X810184Y-124509D01*
X809310Y-126259D01*
X808874Y-128593D01*
X809310Y-130926D01*
X810184Y-132676D01*
X811494Y-133843D01*
X813022Y-134426D01*
X814550Y-134134D01*
X815861Y-133260D01*
X816734Y-132093D01*
G01X825719Y-139676D02*
X827029Y-140259D01*
X828776Y-139676D01*
X829867Y-138510D01*
X830741Y-137051D01*
X832050Y-132385D01*
X834889Y-122760D01*
G01X827902D02*
X832050Y-132385D01*
G01X844529Y-126551D02*
X851516D01*
X850861Y-124509D01*
X849769Y-123343D01*
X848241Y-122760D01*
X846712Y-123051D01*
X845402Y-123926D01*
X844529Y-125968D01*
X844092Y-127718D01*
Y-129468D01*
X844529Y-131218D01*
X845621Y-132968D01*
X846931Y-134134D01*
X848459Y-134426D01*
X849987Y-133843D01*
X851516Y-132093D01*
G01X862247Y-134426D02*
Y-122760D01*
G01Y-125093D02*
X863339Y-123926D01*
X864431Y-123051D01*
X865959Y-122760D01*
X867050Y-123051D01*
X868361Y-123926D01*
G01X879529Y-132385D02*
X880621Y-133551D01*
X882149Y-134426D01*
X883459D01*
X884769Y-133843D01*
X885642Y-132968D01*
X886079Y-131802D01*
X885861Y-130051D01*
X884987Y-129176D01*
X881057Y-127426D01*
X880184Y-125384D01*
X880621Y-123926D01*
X881494Y-123051D01*
X882804Y-122760D01*
X884114Y-123051D01*
X885424Y-123926D01*
G01X756261Y0D02*
G03Y-7874I0J-3937D01*
G01X953111D02*
X756261D01*
G01Y480315D02*
G03Y472441I0J-3937D01*
G01Y960630D02*
G03Y952756I0J-3937D01*
G01X953111Y960630D02*
X756261D01*
G01X812804Y-161926D02*
Y-179426D01*
G01X807782Y-161926D02*
X817826D01*
G01X825719Y-177093D02*
X827466Y-178551D01*
X829431Y-179426D01*
X831177D01*
X832924Y-178551D01*
X834234Y-177093D01*
X834889Y-175051D01*
X834452Y-173010D01*
X833361Y-171259D01*
X831396Y-170093D01*
X828776Y-169509D01*
X827247Y-168343D01*
X826592Y-166301D01*
X827029Y-164259D01*
X828121Y-162801D01*
X829649Y-161926D01*
X831177D01*
X832706Y-162509D01*
X834016Y-163968D01*
G01X842127Y-179426D02*
Y-161926D01*
X847804Y-176509D01*
X853481Y-161926D01*
Y-179426D01*
G01X860501D02*
Y-161926D01*
X864867D01*
X866614Y-162801D01*
X867924Y-163968D01*
X869016Y-165717D01*
X869889Y-167760D01*
X870107Y-170676D01*
X869889Y-173593D01*
X869016Y-175635D01*
X867924Y-177385D01*
X866614Y-178551D01*
X864867Y-179426D01*
X860501D01*
G01X924737Y-175926D02*
X925829Y-177676D01*
X927139Y-178843D01*
X928667Y-179426D01*
X930414Y-178843D01*
X931724Y-177676D01*
X933034Y-175926D01*
X933471Y-173593D01*
Y-161926D01*
G01X946604Y-179426D02*
X944857Y-179134D01*
X943329Y-177968D01*
X942019Y-176218D01*
X941145Y-174176D01*
X940709Y-171843D01*
Y-169509D01*
X941145Y-167176D01*
X942019Y-165134D01*
X943329Y-163385D01*
X944857Y-162218D01*
X946604Y-161926D01*
X948350Y-162218D01*
X949879Y-163385D01*
X951189Y-165134D01*
X952063Y-167176D01*
X952499Y-169509D01*
Y-171843D01*
X952063Y-174176D01*
X951189Y-176218D01*
X949879Y-177968D01*
X948350Y-179134D01*
X946604Y-179426D01*
G01X959519Y-177093D02*
X961266Y-178551D01*
X963231Y-179426D01*
X964977D01*
X966724Y-178551D01*
X968034Y-177093D01*
X968689Y-175051D01*
X968252Y-173010D01*
X967161Y-171259D01*
X965196Y-170093D01*
X962576Y-169509D01*
X961047Y-168343D01*
X960392Y-166301D01*
X960829Y-164259D01*
X961921Y-162801D01*
X963449Y-161926D01*
X964977D01*
X966506Y-162509D01*
X967816Y-163968D01*
G01X985971Y-179426D02*
X977237D01*
Y-161926D01*
X985971D01*
G01X982477Y-170384D02*
X977237D01*
G01X994737Y-179426D02*
Y-161926D01*
X999977D01*
X1001724Y-162801D01*
X1003034Y-164843D01*
X1003471Y-167176D01*
X1003034Y-169509D01*
X1001942Y-171259D01*
X999977Y-172135D01*
X994737D01*
G01X1012019Y-179426D02*
Y-161926D01*
G01X1021189D02*
Y-179426D01*
G01Y-170676D02*
X1012019D01*
G01X1047237Y-161926D02*
Y-179426D01*
X1055971D01*
G01X1063645D02*
X1069104Y-161926D01*
X1074563Y-179426D01*
G01X1072597Y-173301D02*
X1065610D01*
G01X1081801Y-161926D02*
Y-174468D01*
X1082674Y-177093D01*
X1084421Y-178843D01*
X1086604Y-179426D01*
X1088787Y-178843D01*
X1090534Y-177093D01*
X1091407Y-174468D01*
Y-161926D01*
G01X941801Y-134426D02*
Y-116926D01*
X946167D01*
X947914Y-117801D01*
X949224Y-118968D01*
X950316Y-120717D01*
X951189Y-122760D01*
X951407Y-125676D01*
X951189Y-128593D01*
X950316Y-130635D01*
X949224Y-132385D01*
X947914Y-133551D01*
X946167Y-134426D01*
X941801D01*
G01X960829Y-126551D02*
X967816D01*
X967161Y-124509D01*
X966069Y-123343D01*
X964541Y-122760D01*
X963012Y-123051D01*
X961702Y-123926D01*
X960829Y-125968D01*
X960392Y-127718D01*
Y-129468D01*
X960829Y-131218D01*
X961921Y-132968D01*
X963231Y-134134D01*
X964759Y-134426D01*
X966287Y-133843D01*
X967816Y-132093D01*
G01X978329Y-132385D02*
X979421Y-133551D01*
X980949Y-134426D01*
X982259D01*
X983569Y-133843D01*
X984442Y-132968D01*
X984879Y-131802D01*
X984661Y-130051D01*
X983787Y-129176D01*
X979857Y-127426D01*
X978984Y-125384D01*
X979421Y-123926D01*
X980294Y-123051D01*
X981604Y-122760D01*
X982914Y-123051D01*
X984224Y-123926D01*
G01X999104Y-122760D02*
Y-134426D01*
G01Y-118093D02*
X998667Y-117801D01*
Y-117218D01*
X999104Y-116926D01*
X999541Y-117218D01*
Y-117801D01*
X999104Y-118093D01*
G01X1013547Y-138801D02*
X1015076Y-139968D01*
X1016822Y-140259D01*
X1018350Y-139968D01*
X1019661Y-138510D01*
X1020534Y-136468D01*
Y-122760D01*
G01Y-125093D02*
X1019661Y-123926D01*
X1018350Y-123051D01*
X1016822Y-122760D01*
X1015076Y-123343D01*
X1013984Y-124509D01*
X1013110Y-126551D01*
X1012674Y-128593D01*
X1012892Y-130343D01*
X1013766Y-132385D01*
X1015076Y-133843D01*
X1016822Y-134426D01*
X1018132Y-134134D01*
X1019661Y-132968D01*
X1020534Y-131802D01*
G01X1030392Y-134426D02*
Y-122760D01*
G01Y-125676D02*
X1031266Y-124218D01*
X1032576Y-123051D01*
X1034322Y-122760D01*
X1035850Y-123051D01*
X1037161Y-124218D01*
X1037816Y-126259D01*
Y-134426D01*
G01X1048329Y-126551D02*
X1055316D01*
X1054661Y-124509D01*
X1053569Y-123343D01*
X1052041Y-122760D01*
X1050512Y-123051D01*
X1049202Y-123926D01*
X1048329Y-125968D01*
X1047892Y-127718D01*
Y-129468D01*
X1048329Y-131218D01*
X1049421Y-132968D01*
X1050731Y-134134D01*
X1052259Y-134426D01*
X1053787Y-133843D01*
X1055316Y-132093D01*
G01X1066047Y-134426D02*
Y-122760D01*
G01Y-125093D02*
X1067139Y-123926D01*
X1068231Y-123051D01*
X1069759Y-122760D01*
X1070850Y-123051D01*
X1072161Y-123926D01*
G01X953111Y-7874D02*
G03Y0I0J3937D01*
G01Y472441D02*
G03Y480315I0J3937D01*
G01Y952756D02*
G03Y960630I0J3937D01*
G01X983820Y0D02*
G03Y-7874I0J-3937D01*
G01X1180670D02*
X983820D01*
G01Y480315D02*
G03Y472441I0J-3937D01*
G01Y960630D02*
G03Y952756I0J-3937D01*
G01X1180670Y960630D02*
X983820D01*
G01X1112804Y-179426D02*
Y-161926D01*
X1110184Y-165426D01*
G01Y-179426D02*
X1115424D01*
G01X1130304Y-161926D02*
X1128557Y-162509D01*
X1127247Y-163968D01*
X1126374Y-165717D01*
X1125719Y-168051D01*
X1125501Y-170676D01*
X1125719Y-173301D01*
X1126374Y-175635D01*
X1127247Y-177385D01*
X1128557Y-178843D01*
X1130304Y-179426D01*
X1132050Y-178843D01*
X1133361Y-177385D01*
X1134234Y-175635D01*
X1134889Y-173301D01*
X1135107Y-170676D01*
X1134889Y-168051D01*
X1134234Y-165717D01*
X1133361Y-163968D01*
X1132050Y-162509D01*
X1130304Y-161926D01*
G01X1143874Y-180009D02*
X1151734Y-161926D01*
G01X1165304Y-179426D02*
Y-161926D01*
X1162684Y-165426D01*
G01Y-179426D02*
X1167924D01*
G01X1179092Y-177385D02*
X1180621Y-178843D01*
X1182367Y-179426D01*
X1184114Y-178843D01*
X1185642Y-177093D01*
X1186734Y-174468D01*
X1187171Y-171843D01*
Y-168635D01*
X1186734Y-166010D01*
X1185642Y-163676D01*
X1184332Y-162509D01*
X1182804Y-161926D01*
X1181057Y-162509D01*
X1179747Y-163676D01*
X1178874Y-165426D01*
X1178437Y-167760D01*
X1178874Y-169801D01*
X1179966Y-171843D01*
X1181276Y-173010D01*
X1182804Y-173301D01*
X1184550Y-172718D01*
X1185861Y-171259D01*
X1187171Y-168635D01*
G01X1196374Y-180009D02*
X1204234Y-161926D01*
G01X1213656Y-164843D02*
X1214966Y-163093D01*
X1216494Y-162218D01*
X1218241Y-161926D01*
X1220424Y-162509D01*
X1221952Y-163968D01*
X1222389Y-165717D01*
X1222171Y-167468D01*
X1221297Y-168926D01*
X1216931Y-171843D01*
X1214966Y-173884D01*
X1213656Y-176802D01*
X1213219Y-179426D01*
X1222389D01*
G01X1235304Y-161926D02*
X1233557Y-162509D01*
X1232247Y-163968D01*
X1231374Y-165717D01*
X1230719Y-168051D01*
X1230501Y-170676D01*
X1230719Y-173301D01*
X1231374Y-175635D01*
X1232247Y-177385D01*
X1233557Y-178843D01*
X1235304Y-179426D01*
X1237050Y-178843D01*
X1238361Y-177385D01*
X1239234Y-175635D01*
X1239889Y-173301D01*
X1240107Y-170676D01*
X1239889Y-168051D01*
X1239234Y-165717D01*
X1238361Y-163968D01*
X1237050Y-162509D01*
X1235304Y-161926D01*
G01X1252804Y-179426D02*
Y-161926D01*
X1250184Y-165426D01*
G01Y-179426D02*
X1255424D01*
G01X1266156Y-164843D02*
X1267466Y-163093D01*
X1268994Y-162218D01*
X1270741Y-161926D01*
X1272924Y-162509D01*
X1274452Y-163968D01*
X1274889Y-165717D01*
X1274671Y-167468D01*
X1273797Y-168926D01*
X1269431Y-171843D01*
X1267466Y-173884D01*
X1266156Y-176802D01*
X1265719Y-179426D01*
X1274889D01*
G01X1160501Y-134426D02*
Y-116926D01*
X1164867D01*
X1166614Y-117801D01*
X1167924Y-118968D01*
X1169016Y-120717D01*
X1169889Y-122760D01*
X1170107Y-125676D01*
X1169889Y-128593D01*
X1169016Y-130635D01*
X1167924Y-132385D01*
X1166614Y-133551D01*
X1164867Y-134426D01*
X1160501D01*
G01X1186734D02*
Y-122760D01*
G01Y-124801D02*
X1185861Y-123635D01*
X1184550Y-123051D01*
X1183022Y-122760D01*
X1181494Y-123343D01*
X1180184Y-124509D01*
X1179310Y-126259D01*
X1178874Y-128593D01*
X1179310Y-130926D01*
X1180184Y-132676D01*
X1181494Y-133843D01*
X1183022Y-134426D01*
X1184550Y-134134D01*
X1185861Y-133260D01*
X1186734Y-132093D01*
G01X1200304Y-116926D02*
Y-134426D01*
G01X1197247Y-122760D02*
X1203361D01*
G01X1214529Y-126551D02*
X1221516D01*
X1220861Y-124509D01*
X1219769Y-123343D01*
X1218241Y-122760D01*
X1216712Y-123051D01*
X1215402Y-123926D01*
X1214529Y-125968D01*
X1214092Y-127718D01*
Y-129468D01*
X1214529Y-131218D01*
X1215621Y-132968D01*
X1216931Y-134134D01*
X1218459Y-134426D01*
X1219987Y-133843D01*
X1221516Y-132093D01*
G01X1180670Y-7874D02*
G03Y0I0J3937D01*
G01Y472441D02*
G03Y480315I0J3937D01*
G01Y952756D02*
G03Y960630I0J3937D01*
G01X1211380Y-7874D02*
X1284723D01*
G01X1211380Y0D02*
G03Y-7874I0J-3937D01*
G01X1259605Y226378D02*
Y246063D01*
G01X1263542Y250000D02*
G03X1259605Y246063I0J-3937D01*
G01Y226378D02*
G03X1263542Y222441I3937J0D01*
G01X1211380Y480315D02*
G03Y472441I0J-3937D01*
G01X1259605Y706693D02*
Y726378D01*
G01X1263542Y730315D02*
G03X1259605Y726378I0J-3937D01*
G01Y706693D02*
G03X1263542Y702756I3937J0D01*
G01X1211380Y960630D02*
G03Y952756I0J-3937D01*
G01Y960630D02*
X1284723D01*
G01X1317968Y-19685D02*
G03X1331968Y-5685I0J14000D01*
G01X1288660Y102559D02*
Y3937D01*
G01Y102559D02*
Y3937D01*
G01X1284723Y0D02*
G03X1288660Y3937I0J3937D01*
G01X1284723Y0D02*
G03X1288660Y3937I0J3937D01*
G01X1284723Y-7874D02*
G03X1296534Y3937I0J11811D01*
G01D02*
Y45847D01*
G01D02*
G03X1288660I-3937J0D01*
G01X1292597Y106496D02*
G03X1288660Y102559I0J-3937D01*
G01X1292597Y106496D02*
G03X1288660Y102559I0J-3937D01*
G01X1331968Y98622D02*
X1296534D01*
G01D02*
Y71044D01*
G01X1288660D02*
G03X1296534I3937J0D01*
G01X1292597Y106496D02*
X1326061D01*
G01X1292597D02*
X1326061D01*
G01X1301258Y180394D02*
X1326061D01*
G01D02*
X1290038D01*
G01X1301258D02*
X1290038D01*
G01X1326061Y177638D02*
X1290038D01*
G01X1326061D02*
X1290038D01*
G01Y180394D02*
G03Y177638I0J-1378D01*
G01Y180394D02*
G03Y177638I0J-1378D01*
G01X1271416Y246063D02*
Y226378D01*
G01X1263542Y250000D02*
X1267479D01*
G01Y222441D02*
X1263542D01*
G01X1271416Y246063D02*
G03X1267479Y250000I-3937J0D01*
G01Y222441D02*
G03X1271416Y226378I0J3937D01*
G01X1288660Y468504D02*
Y365472D01*
G01Y468504D02*
Y365472D01*
G01X1326061Y361535D02*
X1292597D01*
G01X1326061D02*
X1292597D01*
G01X1288660Y365472D02*
G03X1292597Y361535I3937J0D01*
G01X1288660Y365472D02*
G03X1292597Y361535I3937J0D01*
G01X1331968Y369409D02*
X1296534D01*
G01D02*
Y396985D01*
G01D02*
G03X1288660I-3937J0D01*
G01X1296534Y526162D02*
Y422182D01*
G01X1288660D02*
G03X1296534I3937J0D01*
G01X1288660Y582874D02*
Y484252D01*
G01Y582874D02*
Y484252D01*
G01X1284723Y480315D02*
G03X1288660Y484252I0J3937D01*
G01X1284723Y480315D02*
G03X1288660Y484252I0J3937D01*
G01Y468504D02*
G03X1284723Y472441I-3937J0D01*
G01X1288660Y468504D02*
G03X1284723Y472441I-3937J0D01*
G01X1296534Y578937D02*
Y551359D01*
G01X1288660D02*
G03X1296534I3937J0D01*
G01Y526162D02*
G03X1288660I-3937J0D01*
G01X1292597Y586811D02*
X1326061D01*
G01X1292597D02*
X1326061D01*
G01X1292597D02*
G03X1288660Y582874I0J-3937D01*
G01X1292597Y586811D02*
G03X1288660Y582874I0J-3937D01*
G01X1331968Y578937D02*
X1296534D01*
G01X1301258Y660709D02*
X1326061D01*
G01D02*
X1290038D01*
G01X1301258D02*
X1290038D01*
G01X1326061Y657953D02*
X1290038D01*
G01X1326061D02*
X1290038D01*
G01Y660709D02*
G03Y657953I0J-1378D01*
G01Y660709D02*
G03Y657953I0J-1378D01*
G01X1271416Y726378D02*
Y706693D01*
G01X1263542Y730315D02*
X1267479D01*
G01Y702756D02*
X1263542D01*
G01X1271416Y726378D02*
G03X1267479Y730315I-3937J0D01*
G01Y702756D02*
G03X1271416Y706693I0J3937D01*
G01X1326061Y841850D02*
X1292597D01*
G01X1326061D02*
X1292597D01*
G01X1288660Y845787D02*
G03X1292597Y841850I3937J0D01*
G01X1288660Y845787D02*
G03X1292597Y841850I3937J0D01*
G01X1288660Y948819D02*
Y845787D01*
G01Y948819D02*
Y845787D01*
G01X1296534Y849724D02*
Y877300D01*
G01Y877296D02*
G03X1288660I-3937J0D01*
G01X1296534Y948819D02*
Y902497D01*
G01X1288660D02*
G03X1296534I3937J0D01*
G01X1331968Y849724D02*
X1296534D01*
G01X1288660Y948819D02*
G03X1284723Y952756I-3937J0D01*
G01X1288660Y948819D02*
G03X1284723Y952756I-3937J0D01*
G01X1296534Y948819D02*
G03X1284723Y960630I-11811J0D01*
G01X1331968Y958441D02*
G03X1317968Y972441I-14000J0D01*
G01X1331968Y-5685D02*
Y98622D01*
G01X1331967Y112402D02*
Y171732D01*
G01X1326061Y106496D02*
X1329998Y110433D01*
G01X1326061Y106496D02*
X1331967Y112402D01*
G01Y186299D02*
Y355630D01*
G01X1326061Y180394D02*
X1329998Y184331D01*
G01X1326061Y180394D02*
X1331967Y186299D01*
G01Y171732D02*
X1326061Y177638D01*
G01X1329998Y173701D02*
X1326061Y177638D01*
G01X1331967Y355630D02*
X1326061Y361535D01*
G01X1329998Y357598D02*
X1326061Y361535D01*
G01X1331968Y578937D02*
Y369409D01*
G01X1331967Y592717D02*
Y652047D01*
G01X1326061Y586811D02*
X1329998Y590748D01*
G01X1326061Y586811D02*
X1331967Y592717D01*
G01Y666614D02*
Y835945D01*
G01X1326061Y660709D02*
X1329998Y664646D01*
G01X1326061Y660709D02*
X1331967Y666614D01*
G01Y652047D02*
X1326061Y657953D01*
G01X1329998Y654016D02*
X1326061Y657953D01*
G01X1331967Y835945D02*
X1326061Y841850D01*
G01X1329998Y837913D02*
X1326061Y841850D01*
G01X1331968Y958441D02*
Y849724D01*
G54D14*
X30108Y374132D03*
Y368932D03*
X35198Y337936D03*
Y333436D03*
X66150Y378236D03*
X66147Y373979D03*
X66098Y369470D03*
X534333Y263971D03*
Y268971D03*
X522800Y326000D03*
X530236Y326402D03*
X530136Y330602D03*
X530236Y322102D03*
G54D23*
X41309Y387463D03*
G54D15*
X43072Y365847D03*
X43159Y373885D03*
X55352Y387374D03*
X60052Y387292D03*
X51094Y387325D03*
X538000Y293300D03*
X583000Y76800D03*
G54D24*
X41309Y391063D03*
G54D16*
X43072Y369247D03*
X43159Y377285D03*
X55352Y390774D03*
X60052Y390692D03*
X51094Y390725D03*
X538000Y296700D03*
X583000Y80200D03*
G54D25*
X66091Y365163D03*
X577707Y66918D03*
X522800Y322000D03*
X530136Y334902D03*
G54D26*
X69491Y365163D03*
X526200Y322000D03*
X533536Y334902D03*
X581107Y66918D03*
G54D17*
X57398Y355860D03*
X48325Y355850D03*
X52705Y355795D03*
G54D18*
X57398Y352460D03*
X48325Y352450D03*
X52705Y352395D03*
G54D27*
X462000Y192300D03*
Y180700D03*
X448500Y192300D03*
Y180700D03*
X435000Y192300D03*
Y180700D03*
X421500Y192300D03*
Y180700D03*
G54D28*
X512989Y198162D03*
Y173362D03*
X487625Y198086D03*
Y173286D03*
X538135Y198177D03*
Y173377D03*
G54D19*
X45807Y388068D03*
X38128Y374332D03*
X542500Y269171D03*
X634488Y72003D03*
G54D29*
X529011Y293257D03*
X532886Y300757D03*
X525136D03*
X529036Y308352D03*
X525161Y315852D03*
X532911D03*
M02*
